(kicad_pcb
	(version 20241229)
	(generator "pcbnew")
	(generator_version "9.0")
	(general
		(thickness 1.63)
		(legacy_teardrops no)
	)
	(paper "A4")
	(title_block
		(title "CM4 Baseboard")
		(date "2026-01-05")
		(rev "1.1.1")
		(company "Antmicro Ltd")
		(comment 1 "www.antmicro.com")
		(comment 9 "footprints 506-506 of 506")
	)
	(layers
		(0 "F.Cu" signal)
		(4 "In1.Cu" power)
		(6 "In2.Cu" power)
		(8 "In3.Cu" signal)
		(10 "In4.Cu" signal)
		(2 "B.Cu" signal)
		(9 "F.Adhes" user "F.Adhesive")
		(11 "B.Adhes" user "B.Adhesive")
		(13 "F.Paste" user)
		(15 "B.Paste" user)
		(5 "F.SilkS" user "F.Silkscreen")
		(7 "B.SilkS" user "B.Silkscreen")
		(1 "F.Mask" user)
		(3 "B.Mask" user)
		(17 "Dwgs.User" user "User.Drawings")
		(19 "Cmts.User" user "User.Comments")
		(21 "Eco1.User" user "User.Eco1")
		(23 "Eco2.User" user "User.Eco2")
		(25 "Edge.Cuts" user)
		(27 "Margin" user)
		(31 "F.CrtYd" user "F.Courtyard")
		(29 "B.CrtYd" user "B.Courtyard")
		(35 "F.Fab" user)
		(33 "B.Fab" user)
	)
	(footprint "antmicro-footprints:MS621FE-FL11E"
		(layer "B.Cu")
		(at 130.6 174.6 -135)
		(property "Reference" "BT801"
			(at -1.838478 -8.202439 0)
			(layer "B.SilkS")
			(effects
				(font
					(size 0.7 0.7)
					(thickness 0.15)
				)
				(justify left bottom mirror)
			)
		)
		(property "Value" "Battery_Holder_MS621FE-FL11E"
			(at -0.001 -6.2 45)
			(layer "B.Fab")
			(effects
				(font
					(size 0.7 0.7)
					(thickness 0.15)
				)
				(justify left bottom mirror)
			)
		)
		(property "Datasheet" "https://www.sii.co.jp/en/me/datasheets/ms-rechargeable/ms621fe/"
			(at 0 0 45)
			(layer "B.Fab")
			(hide yes)
			(effects
				(font
					(size 1.27 1.27)
					(thickness 0.15)
				)
				(justify mirror)
			)
		)
		(property "Description" "Rechargeable Battery, Coin Cell, Single Cell, 3 V, Lithium Manganese Dioxide, 5.5 mAh, Button Cell"
			(at 0 0 45)
			(layer "B.Fab")
			(hide yes)
			(effects
				(font
					(size 1.27 1.27)
					(thickness 0.15)
				)
				(justify mirror)
			)
		)
		(property "Manufacturer" "Seiko Instruments"
			(at 0 0 225)
			(unlocked yes)
			(layer "B.Fab")
			(hide yes)
			(effects
				(font
					(size 1 1)
					(thickness 0.15)
				)
				(justify mirror)
			)
		)
		(property "MPN" "MS621FE-FL11E"
			(at 0 0 225)
			(unlocked yes)
			(layer "B.Fab")
			(hide yes)
			(effects
				(font
					(size 1 1)
					(thickness 0.15)
				)
				(justify mirror)
			)
		)
		(property "Author" "Antmicro"
			(at 0 0 225)
			(unlocked yes)
			(layer "B.Fab")
			(hide yes)
			(effects
				(font
					(size 1 1)
					(thickness 0.15)
				)
				(justify mirror)
			)
		)
		(property "License" "Apache-2.0"
			(at 0 0 225)
			(unlocked yes)
			(layer "B.Fab")
			(hide yes)
			(effects
				(font
					(size 1 1)
					(thickness 0.15)
				)
				(justify mirror)
			)
		)
		(sheetname "/Peripherals/")
		(sheetfile "peripherals.kicad_sch")
		(attr smd)
		(fp_arc
			(start -1.200001 2.15)
			(mid 0 -4.834001)
			(end 1.200001 2.15)
			(stroke
				(width 0.15)
				(type solid)
			)
			(layer "B.SilkS")
		)
		(fp_line
			(start 1.275 5.2)
			(end -1.275 5.2)
			(stroke
				(width 0.05)
				(type solid)
			)
			(layer "B.CrtYd")
		)
		(fp_line
			(start 1.275 5.2)
			(end 1.275 2.425)
			(stroke
				(width 0.05)
				(type solid)
			)
			(layer "B.CrtYd")
		)
		(fp_line
			(start -1.275 5.2)
			(end -1.275 2.425)
			(stroke
				(width 0.05)
				(type solid)
			)
			(layer "B.CrtYd")
		)
		(fp_arc
			(start -1.275 2.425)
			(mid 0 -5.143375)
			(end 1.275 2.425)
			(stroke
				(width 0.05)
				(type solid)
			)
			(layer "B.CrtYd")
		)
		(fp_line
			(start 1.2 5.05)
			(end -0.8 5.05)
			(stroke
				(width 0.15)
				(type solid)
			)
			(layer "B.Fab")
		)
		(fp_line
			(start 1.2 5.05)
			(end 1.2 2.04)
			(stroke
				(width 0.15)
				(type solid)
			)
			(layer "B.Fab")
		)
		(fp_line
			(start -0.8 5.05)
			(end -1.200001 4.65)
			(stroke
				(width 0.15)
				(type solid)
			)
			(layer "B.Fab")
		)
		(fp_line
			(start -1.200001 4.65)
			(end -1.2 2.04)
			(stroke
				(width 0.15)
				(type solid)
			)
			(layer "B.Fab")
		)
		(fp_circle
			(center -0.001001 -1.25)
			(end -0.001 2.25)
			(stroke
				(width 0.15)
				(type solid)
			)
			(fill no)
			(layer "B.Fab")
		)
		(fp_text user "${REFERENCE}"
			(at -3.501 -11.8 45)
			(layer "B.Fab")
			(effects
				(font
					(size 0.7 0.7)
					(thickness 0.15)
				)
				(justify left bottom mirror)
			)
		)
		(fp_text user "COPPER KEEPOUT"
			(at -0.2 3.14 135)
			(unlocked yes)
			(layer "B.Fab")
			(effects
				(font
					(size 0.4 0.4)
					(thickness 0.1)
				)
				(justify left bottom mirror)
			)
		)
		(fp_text user "License: Apache-2.0"
			(at -3.501 -8.2 45)
			(layer "B.Fab")
			(effects
				(font
					(size 0.7 0.7)
					(thickness 0.15)
				)
				(justify left bottom mirror)
			)
		)
		(fp_text user "Author: Antmicro"
			(at -3.501 -9.4 45)
			(layer "B.Fab")
			(effects
				(font
					(size 0.7 0.7)
					(thickness 0.15)
				)
				(justify left bottom mirror)
			)
		)
		(pad "1" smd rect
			(at -0.750001 4.05 315)
			(size 1.8 0.75)
			(layers "B.Cu" "B.Mask" "B.Paste")
			(net 502 "Net-(BT801-+)")
			(pinfunction "+")
			(pintype "passive")
		)
		(pad "2" smd rect
			(at 0.750001 4.05 315)
			(size 1.8 0.75)
			(layers "B.Cu" "B.Mask" "B.Paste")
			(net 3 "GND")
			(pinfunction "-")
			(pintype "passive")
		)
		(zone
			(net 0)
			(net_name "")
			(layers "B.Cu" "B.CrtYd")
			(hatch edge 0.508)
			(connect_pads
				(clearance 0)
			)
			(min_thickness 0.254)
			(filled_areas_thickness no)
			(keepout
				(tracks allowed)
				(vias not_allowed)
				(pads not_allowed)
				(copperpour not_allowed)
				(footprints allowed)
			)
			(placement
				(enabled no)
				(sheetname "")
			)
			(fill
				(thermal_gap 0.508)
				(thermal_bridge_width 0.508)
			)
			(polygon
				(pts
					(xy 133.188011 175.547523) (xy 129.199929 171.559441) (xy 127.559441 173.199929) (xy 131.547523 177.188011)
				)
			)
		)
	)
)
